FILE_TYPE = MULTI_PHYS_TABLE;

PART 'SCONN75K_APCI0155P004A'

{========================================================================================}
:VALUE                     | PART_TYPE | MATERIAL | PART_NUMBER    = STANDARD | LIFECYCLE          | PART_NUMBER   | JEDEC_TYPE                            | DESCRIPTION                             | MANUFTR | MANUF_PN         | RD_CMPLS_LVL | CMPLS_LVL | CLASS | DIP_SMD | FROM_PJ    | DATA                     | FP_ECN | EE_CHECK_LIST | CREATOR | CREATEDAY  | PSL | STATUS ;
{========================================================================================}
 'SCONN75K_APCI0155-P004A' | 'SMLF'    | 'IO'     | 'DFHS75FR313'(!) = ''       | ''               | 'DFHS75FR313' |'CON_F67S2H2D2S_P0-5W7-55_LUVXB_H270'| 'CONN SMD HOUSING 75P 2R FR(P0.5,H6.7)' | 'LTS'   | 'APCI0155-P004A' | 'EP(V1)'     | ''        | 'IO'  | ''      | 'F08-MARK' | 'LTS_APCI0155-P004A.pdf' | ''     | ''            | ''      | '20160104' | ''  | ''    
 'SCONN75K_APCI0155-P004A' | 'SMLF'    | 'EMPTY'  | 'DFHS75FR313'(!) = ''       | ''               | 'DFHS75FR313' |'CON_F67S2H2D2S_P0-5W7-55_LUVXB_H270'| 'CONN SMD HOUSING 75P 2R FR(P0.5,H6.7)' | 'LTS'   | 'APCI0155-P004A' | 'EP(V1)'     | ''        | 'IO'  | ''      | 'F08-MARK' | 'LTS_APCI0155-P004A.pdf' | ''     | ''            | ''      | '20160104' | ''  | ''    

END_PART

END.

